(kicad_pcb
	(version 20260206)
	(generator "pcbnew")
	(generator_version "10.0")
	(general
		(thickness 1.6)
		(legacy_teardrops no)
	)
	(paper "A4")
	(title_block
		(title "01162023_DA0F0TEBIF0_F0T_Expander_BD_F_brd_V02_OCP.brd")
		(comment 1 "Grand Teton / footprints 3106-3112 of 9728")
	)
	(layers
		(0 "F.Cu" signal "TOP")
		(4 "In1.Cu" signal "GND")
		(6 "In2.Cu" signal "VCC")
		(8 "In3.Cu" signal "VCC1")
		(10 "In4.Cu" signal "GND1")
		(12 "In5.Cu" signal "IN1")
		(14 "In6.Cu" signal "GND2")
		(16 "In7.Cu" signal "IN2")
		(18 "In8.Cu" signal "GND3")
		(20 "In9.Cu" signal "IN3")
		(22 "In10.Cu" signal "GND4")
		(24 "In11.Cu" signal "IN4")
		(26 "In12.Cu" signal "GND5")
		(28 "In13.Cu" signal "IN5")
		(30 "In14.Cu" signal "GND6")
		(32 "In15.Cu" signal "IN6")
		(34 "In16.Cu" signal "GND7")
		(2 "B.Cu" signal "BOTTOM")
		(9 "F.Adhes" user "F.Adhesive")
		(11 "B.Adhes" user "B.Adhesive")
		(13 "F.Paste" user "Package Geometry/Pastemask Top")
		(15 "B.Paste" user "Package Geometry/Pastemask Bottom")
		(5 "F.SilkS" user "Ref Des/Silkscreen Top")
		(7 "B.SilkS" user "Ref Des/Silkscreen Bottom")
		(1 "F.Mask" user "Board Geometry/Soldermask Top")
		(3 "B.Mask" user "Board Geometry/Soldermask Bottom")
		(17 "Dwgs.User" user "User.Drawings")
		(19 "Cmts.User" user "User.Comments")
		(21 "Eco1.User" user "User.Eco1")
		(23 "Eco2.User" user "User.Eco2")
		(25 "Edge.Cuts" user "Board Geometry/Outline")
		(27 "Margin" user)
		(31 "F.CrtYd" user "Package Geometry/Place Bound Top")
		(29 "B.CrtYd" user "Package Geometry/Place Bound Bottom")
		(35 "F.Fab" user "Ref Des/Assembly Top")
		(33 "B.Fab" user "Ref Des/Assembly Bottom")
	)
	(footprint ""
		(layer "F.Cu")
		(at 441.200032 -289.230816 -90)
		(property "Reference" "R3997"
			(at 0 0 270)
			(layer "F.SilkS")
			(hide yes)
			(effects
				(font
					(size 1.27 1.27)
				)
			)
		)
		(property "Value" ""
			(at 0 0 270)
			(layer "F.Fab")
			(effects
				(font
					(size 1.27 1.27)
				)
			)
		)
		(duplicate_pad_numbers_are_jumpers no)
		(fp_line
			(start -0.7874 0.4064)
			(end -0.7874 -0.4064)
			(stroke
				(width 0.1524)
				(type default)
			)
			(layer "F.SilkS")
		)
		(fp_line
			(start 0.7874 0.4064)
			(end -0.7874 0.4064)
			(stroke
				(width 0.1524)
				(type default)
			)
			(layer "F.SilkS")
		)
		(fp_line
			(start -0.7874 -0.4064)
			(end 0.7874 -0.4064)
			(stroke
				(width 0.1524)
				(type default)
			)
			(layer "F.SilkS")
		)
		(fp_line
			(start 0.7874 -0.4064)
			(end 0.7874 0.4064)
			(stroke
				(width 0.1524)
				(type default)
			)
			(layer "F.SilkS")
		)
		(fp_line
			(start -0.67945 0.3048)
			(end -0.67945 -0.305054)
			(stroke
				(width 0.1)
				(type default)
			)
			(layer "F.Fab")
		)
		(fp_line
			(start -0.12065 0.3048)
			(end -0.67945 0.3048)
			(stroke
				(width 0.1)
				(type default)
			)
			(layer "F.Fab")
		)
		(fp_line
			(start 0.120396 0.3048)
			(end 0.120396 0.2794)
			(stroke
				(width 0.1)
				(type default)
			)
			(layer "F.Fab")
		)
		(fp_line
			(start 0.67945 0.3048)
			(end 0.120396 0.3048)
			(stroke
				(width 0.1)
				(type default)
			)
			(layer "F.Fab")
		)
		(fp_line
			(start -0.12065 0.2794)
			(end -0.12065 0.3048)
			(stroke
				(width 0.1)
				(type default)
			)
			(layer "F.Fab")
		)
		(fp_line
			(start 0.120396 0.2794)
			(end -0.12065 0.2794)
			(stroke
				(width 0.1)
				(type default)
			)
			(layer "F.Fab")
		)
		(fp_line
			(start -0.12065 -0.2794)
			(end 0.12065 -0.2794)
			(stroke
				(width 0.1)
				(type default)
			)
			(layer "F.Fab")
		)
		(fp_line
			(start 0.12065 -0.2794)
			(end 0.12065 -0.3048)
			(stroke
				(width 0.1)
				(type default)
			)
			(layer "F.Fab")
		)
		(fp_line
			(start 0.12065 -0.3048)
			(end 0.67945 -0.3048)
			(stroke
				(width 0.1)
				(type default)
			)
			(layer "F.Fab")
		)
		(fp_line
			(start 0.67945 -0.3048)
			(end 0.67945 0.3048)
			(stroke
				(width 0.1)
				(type default)
			)
			(layer "F.Fab")
		)
		(fp_line
			(start -0.67945 -0.305054)
			(end -0.12065 -0.305054)
			(stroke
				(width 0.1)
				(type default)
			)
			(layer "F.Fab")
		)
		(fp_line
			(start -0.12065 -0.305054)
			(end -0.12065 -0.2794)
			(stroke
				(width 0.1)
				(type default)
			)
			(layer "F.Fab")
		)
		(pad "1" smd circle
			(at -0.40005 0 270)
			(size 0 0)
			(layers "F.Cu" "F.Mask" "F.Paste")
			(net "SMB_PEX3_HOST_LS_SCL")
		)
		(pad "2" smd circle
			(at 0.40005 0 270)
			(size 0 0)
			(layers "F.Cu" "F.Mask" "F.Paste")
			(net "P3V3_AUX")
		)
	)
	(footprint ""
		(layer "F.Cu")
		(at 221.251272 -145.974562 180)
		(property "Reference" "R4193"
			(at 0 0 180)
			(layer "F.SilkS")
			(hide yes)
			(effects
				(font
					(size 1.27 1.27)
				)
			)
		)
		(property "Value" ""
			(at 0 0 180)
			(layer "F.Fab")
			(effects
				(font
					(size 1.27 1.27)
				)
			)
		)
		(duplicate_pad_numbers_are_jumpers no)
		(fp_line
			(start 0.7874 0.4064)
			(end -0.7874 0.4064)
			(stroke
				(width 0.1524)
				(type default)
			)
			(layer "F.SilkS")
		)
		(fp_line
			(start 0.7874 -0.4064)
			(end 0.7874 0.4064)
			(stroke
				(width 0.1524)
				(type default)
			)
			(layer "F.SilkS")
		)
		(fp_line
			(start -0.7874 0.4064)
			(end -0.7874 -0.4064)
			(stroke
				(width 0.1524)
				(type default)
			)
			(layer "F.SilkS")
		)
		(fp_line
			(start -0.7874 -0.4064)
			(end 0.7874 -0.4064)
			(stroke
				(width 0.1524)
				(type default)
			)
			(layer "F.SilkS")
		)
		(fp_line
			(start 0.67945 0.3048)
			(end 0.120396 0.3048)
			(stroke
				(width 0.1)
				(type default)
			)
			(layer "F.Fab")
		)
		(fp_line
			(start 0.67945 -0.3048)
			(end 0.67945 0.3048)
			(stroke
				(width 0.1)
				(type default)
			)
			(layer "F.Fab")
		)
		(fp_line
			(start 0.12065 -0.2794)
			(end 0.12065 -0.3048)
			(stroke
				(width 0.1)
				(type default)
			)
			(layer "F.Fab")
		)
		(fp_line
			(start 0.12065 -0.3048)
			(end 0.67945 -0.3048)
			(stroke
				(width 0.1)
				(type default)
			)
			(layer "F.Fab")
		)
		(fp_line
			(start 0.120396 0.3048)
			(end 0.120396 0.2794)
			(stroke
				(width 0.1)
				(type default)
			)
			(layer "F.Fab")
		)
		(fp_line
			(start 0.120396 0.2794)
			(end -0.12065 0.2794)
			(stroke
				(width 0.1)
				(type default)
			)
			(layer "F.Fab")
		)
		(fp_line
			(start -0.12065 0.3048)
			(end -0.67945 0.3048)
			(stroke
				(width 0.1)
				(type default)
			)
			(layer "F.Fab")
		)
		(fp_line
			(start -0.12065 0.2794)
			(end -0.12065 0.3048)
			(stroke
				(width 0.1)
				(type default)
			)
			(layer "F.Fab")
		)
		(fp_line
			(start -0.12065 -0.2794)
			(end 0.12065 -0.2794)
			(stroke
				(width 0.1)
				(type default)
			)
			(layer "F.Fab")
		)
		(fp_line
			(start -0.12065 -0.305054)
			(end -0.12065 -0.2794)
			(stroke
				(width 0.1)
				(type default)
			)
			(layer "F.Fab")
		)
		(fp_line
			(start -0.67945 0.3048)
			(end -0.67945 -0.305054)
			(stroke
				(width 0.1)
				(type default)
			)
			(layer "F.Fab")
		)
		(fp_line
			(start -0.67945 -0.305054)
			(end -0.12065 -0.305054)
			(stroke
				(width 0.1)
				(type default)
			)
			(layer "F.Fab")
		)
		(pad "1" smd circle
			(at -0.40005 0 180)
			(size 0 0)
			(layers "F.Cu" "F.Mask" "F.Paste")
			(net "PU_CK440_PEX_SHFT_LD_N")
		)
		(pad "2" smd circle
			(at 0.40005 0 180)
			(size 0 0)
			(layers "F.Cu" "F.Mask" "F.Paste")
			(net "P3V3")
		)
	)
	(footprint ""
		(layer "F.Cu")
		(at 70.673722 -356.244906 90)
		(property "Reference" "C117"
			(at 0 0 90)
			(layer "F.SilkS")
			(hide yes)
			(effects
				(font
					(size 1.27 1.27)
				)
			)
		)
		(property "Value" ""
			(at 0 0 90)
			(layer "F.Fab")
			(effects
				(font
					(size 1.27 1.27)
				)
			)
		)
		(duplicate_pad_numbers_are_jumpers no)
		(fp_line
			(start 0.299974 -0.150114)
			(end 0.299974 0.150114)
			(stroke
				(width 0.1)
				(type default)
			)
			(layer "F.Fab")
		)
		(fp_line
			(start -0.299974 -0.150114)
			(end 0.299974 -0.150114)
			(stroke
				(width 0.1)
				(type default)
			)
			(layer "F.Fab")
		)
		(fp_line
			(start 0.299974 0.150114)
			(end -0.299974 0.150114)
			(stroke
				(width 0.1)
				(type default)
			)
			(layer "F.Fab")
		)
		(fp_line
			(start -0.299974 0.150114)
			(end -0.299974 -0.150114)
			(stroke
				(width 0.1)
				(type default)
			)
			(layer "F.Fab")
		)
		(pad "1" smd rect
			(at -0.2667 0 90)
			(size 0.3048 0.381)
			(layers "F.Cu" "F.Mask" "F.Paste")
			(net "P5E_PEX0_STN5_TX_DP<85>")
		)
		(pad "2" smd rect
			(at 0.2667 0 90)
			(size 0.3048 0.381)
			(layers "F.Cu" "F.Mask" "F.Paste")
			(net "P5E_PEX0_STN5_TX_C_DP<85>")
		)
	)
	(footprint ""
		(layer "F.Cu")
		(at 420.959534 -61.612526)
		(property "Reference" "PD121"
			(at -3.7084 -2.733548 0)
			(unlocked yes)
			(layer "F.SilkS")
			(effects
				(font
					(size 0.7874 0.5842)
					(thickness 0.1524)
				)
				(justify left)
			)
		)
		(property "Value" ""
			(at 0 0 0)
			(layer "F.Fab")
			(effects
				(font
					(size 1.27 1.27)
				)
			)
		)
		(duplicate_pad_numbers_are_jumpers no)
		(fp_line
			(start -3.656584 -1.970024)
			(end -3.656584 1.970024)
			(stroke
				(width 0.1524)
				(type default)
			)
			(layer "F.SilkS")
		)
		(fp_line
			(start -3.656584 1.970024)
			(end 4.240784 1.970024)
			(stroke
				(width 0.1524)
				(type default)
			)
			(layer "F.SilkS")
		)
		(fp_line
			(start 4.240784 -1.970024)
			(end -3.656584 -1.970024)
			(stroke
				(width 0.1524)
				(type default)
			)
			(layer "F.SilkS")
		)
		(fp_line
			(start 4.240784 1.970024)
			(end 4.240784 -1.970024)
			(stroke
				(width 0.1524)
				(type default)
			)
			(layer "F.SilkS")
		)
		(fp_poly
			(pts
				(xy 3.580384 1.970024) (xy 3.580384 -1.970024) (xy 4.240784 -1.970024) (xy 4.240784 1.970024)
			)
			(stroke
				(width 0)
				(type default)
			)
			(fill yes)
			(layer "F.SilkS")
		)
		(fp_line
			(start -2.3749 -1.970024)
			(end -2.3749 1.970024)
			(stroke
				(width 0.1)
				(type default)
			)
			(layer "F.Fab")
		)
		(fp_line
			(start -2.3749 1.970024)
			(end 2.3749 1.970024)
			(stroke
				(width 0.1)
				(type default)
			)
			(layer "F.Fab")
		)
		(fp_line
			(start 2.3749 -1.970024)
			(end -2.3749 -1.970024)
			(stroke
				(width 0.1)
				(type default)
			)
			(layer "F.Fab")
		)
		(fp_line
			(start 2.3749 1.970024)
			(end 2.3749 -1.970024)
			(stroke
				(width 0.1)
				(type default)
			)
			(layer "F.Fab")
		)
		(fp_text user "+"
			(at -4.9784 -0.23495 0)
			(unlocked yes)
			(layer "F.Fab")
			(effects
				(font
					(size 1.905 1.4224)
					(thickness 0.1524)
				)
				(justify left)
			)
		)
		(fp_text user "-"
			(at 4.1656 -0.23495 0)
			(unlocked yes)
			(layer "F.Fab")
			(effects
				(font
					(size 1.905 1.4224)
					(thickness 0.1524)
				)
				(justify left)
			)
		)
		(pad "A" smd rect
			(at -2.450084 0)
			(size 2.159 2.2606)
			(layers "F.Cu" "F.Mask" "F.Paste")
			(net "GND")
		)
		(pad "C" smd rect
			(at 2.450084 0)
			(size 2.159 2.2606)
			(layers "F.Cu" "F.Mask" "F.Paste")
			(net "P12V_AUX")
		)
	)
	(footprint ""
		(layer "F.Cu")
		(at 131.422648 -193.143378 90)
		(property "Reference" "C4448"
			(at 0 0 90)
			(layer "F.SilkS")
			(hide yes)
			(effects
				(font
					(size 1.27 1.27)
				)
			)
		)
		(property "Value" ""
			(at 0 0 90)
			(layer "F.Fab")
			(effects
				(font
					(size 1.27 1.27)
				)
			)
		)
		(duplicate_pad_numbers_are_jumpers no)
		(fp_line
			(start 0.7874 -0.4064)
			(end 0.7874 0.4064)
			(stroke
				(width 0.1524)
				(type default)
			)
			(layer "F.SilkS")
		)
		(fp_line
			(start -0.7874 -0.4064)
			(end 0.7874 -0.4064)
			(stroke
				(width 0.1524)
				(type default)
			)
			(layer "F.SilkS")
		)
		(fp_line
			(start 0.7874 0.4064)
			(end -0.7874 0.4064)
			(stroke
				(width 0.1524)
				(type default)
			)
			(layer "F.SilkS")
		)
		(fp_line
			(start -0.7874 0.4064)
			(end -0.7874 -0.4064)
			(stroke
				(width 0.1524)
				(type default)
			)
			(layer "F.SilkS")
		)
		(fp_line
			(start -0.12065 -0.305054)
			(end -0.12065 -0.2794)
			(stroke
				(width 0.1)
				(type default)
			)
			(layer "F.Fab")
		)
		(fp_line
			(start -0.67945 -0.305054)
			(end -0.12065 -0.305054)
			(stroke
				(width 0.1)
				(type default)
			)
			(layer "F.Fab")
		)
		(fp_line
			(start 0.67945 -0.3048)
			(end 0.67945 0.3048)
			(stroke
				(width 0.1)
				(type default)
			)
			(layer "F.Fab")
		)
		(fp_line
			(start 0.12065 -0.3048)
			(end 0.67945 -0.3048)
			(stroke
				(width 0.1)
				(type default)
			)
			(layer "F.Fab")
		)
		(fp_line
			(start 0.12065 -0.2794)
			(end 0.12065 -0.3048)
			(stroke
				(width 0.1)
				(type default)
			)
			(layer "F.Fab")
		)
		(fp_line
			(start -0.12065 -0.2794)
			(end 0.12065 -0.2794)
			(stroke
				(width 0.1)
				(type default)
			)
			(layer "F.Fab")
		)
		(fp_line
			(start 0.120396 0.2794)
			(end -0.12065 0.2794)
			(stroke
				(width 0.1)
				(type default)
			)
			(layer "F.Fab")
		)
		(fp_line
			(start -0.12065 0.2794)
			(end -0.12065 0.3048)
			(stroke
				(width 0.1)
				(type default)
			)
			(layer "F.Fab")
		)
		(fp_line
			(start 0.67945 0.3048)
			(end 0.120396 0.3048)
			(stroke
				(width 0.1)
				(type default)
			)
			(layer "F.Fab")
		)
		(fp_line
			(start 0.120396 0.3048)
			(end 0.120396 0.2794)
			(stroke
				(width 0.1)
				(type default)
			)
			(layer "F.Fab")
		)
		(fp_line
			(start -0.12065 0.3048)
			(end -0.67945 0.3048)
			(stroke
				(width 0.1)
				(type default)
			)
			(layer "F.Fab")
		)
		(fp_line
			(start -0.67945 0.3048)
			(end -0.67945 -0.305054)
			(stroke
				(width 0.1)
				(type default)
			)
			(layer "F.Fab")
		)
		(pad "1" smd circle
			(at -0.40005 0 90)
			(size 0 0)
			(layers "F.Cu" "F.Mask" "F.Paste")
			(net "GND")
		)
		(pad "2" smd circle
			(at 0.40005 0 90)
			(size 0 0)
			(layers "F.Cu" "F.Mask" "F.Paste")
			(net "P3V3_AUX")
		)
	)
	(footprint ""
		(layer "F.Cu")
		(at 235.871512 -231.416606 90)
		(property "Reference" "R4521"
			(at 0 0 90)
			(layer "F.SilkS")
			(hide yes)
			(effects
				(font
					(size 1.27 1.27)
				)
			)
		)
		(property "Value" ""
			(at 0 0 90)
			(layer "F.Fab")
			(effects
				(font
					(size 1.27 1.27)
				)
			)
		)
		(duplicate_pad_numbers_are_jumpers no)
		(fp_line
			(start 0.7874 -0.4064)
			(end 0.7874 0.4064)
			(stroke
				(width 0.1524)
				(type default)
			)
			(layer "F.SilkS")
		)
		(fp_line
			(start -0.7874 -0.4064)
			(end 0.7874 -0.4064)
			(stroke
				(width 0.1524)
				(type default)
			)
			(layer "F.SilkS")
		)
		(fp_line
			(start 0.7874 0.4064)
			(end -0.7874 0.4064)
			(stroke
				(width 0.1524)
				(type default)
			)
			(layer "F.SilkS")
		)
		(fp_line
			(start -0.7874 0.4064)
			(end -0.7874 -0.4064)
			(stroke
				(width 0.1524)
				(type default)
			)
			(layer "F.SilkS")
		)
		(fp_line
			(start -0.12065 -0.305054)
			(end -0.12065 -0.2794)
			(stroke
				(width 0.1)
				(type default)
			)
			(layer "F.Fab")
		)
		(fp_line
			(start -0.67945 -0.305054)
			(end -0.12065 -0.305054)
			(stroke
				(width 0.1)
				(type default)
			)
			(layer "F.Fab")
		)
		(fp_line
			(start 0.67945 -0.3048)
			(end 0.67945 0.3048)
			(stroke
				(width 0.1)
				(type default)
			)
			(layer "F.Fab")
		)
		(fp_line
			(start 0.12065 -0.3048)
			(end 0.67945 -0.3048)
			(stroke
				(width 0.1)
				(type default)
			)
			(layer "F.Fab")
		)
		(fp_line
			(start 0.12065 -0.2794)
			(end 0.12065 -0.3048)
			(stroke
				(width 0.1)
				(type default)
			)
			(layer "F.Fab")
		)
		(fp_line
			(start -0.12065 -0.2794)
			(end 0.12065 -0.2794)
			(stroke
				(width 0.1)
				(type default)
			)
			(layer "F.Fab")
		)
		(fp_line
			(start 0.120396 0.2794)
			(end -0.12065 0.2794)
			(stroke
				(width 0.1)
				(type default)
			)
			(layer "F.Fab")
		)
		(fp_line
			(start -0.12065 0.2794)
			(end -0.12065 0.3048)
			(stroke
				(width 0.1)
				(type default)
			)
			(layer "F.Fab")
		)
		(fp_line
			(start 0.67945 0.3048)
			(end 0.120396 0.3048)
			(stroke
				(width 0.1)
				(type default)
			)
			(layer "F.Fab")
		)
		(fp_line
			(start 0.120396 0.3048)
			(end 0.120396 0.2794)
			(stroke
				(width 0.1)
				(type default)
			)
			(layer "F.Fab")
		)
		(fp_line
			(start -0.12065 0.3048)
			(end -0.67945 0.3048)
			(stroke
				(width 0.1)
				(type default)
			)
			(layer "F.Fab")
		)
		(fp_line
			(start -0.67945 0.3048)
			(end -0.67945 -0.305054)
			(stroke
				(width 0.1)
				(type default)
			)
			(layer "F.Fab")
		)
		(pad "1" smd circle
			(at -0.40005 0 90)
			(size 0 0)
			(layers "F.Cu" "F.Mask" "F.Paste")
			(net "SSD7_PWRDIS_BIC")
		)
		(pad "2" smd circle
			(at 0.40005 0 90)
			(size 0 0)
			(layers "F.Cu" "F.Mask" "F.Paste")
			(net "SSD7_PWRDIS_BIC_R")
		)
	)
	(footprint ""
		(layer "F.Cu")
		(at 360.401362 -118.343426 -90)
		(property "Reference" "R6050"
			(at 0 0 270)
			(layer "F.SilkS")
			(hide yes)
			(effects
				(font
					(size 1.27 1.27)
				)
			)
		)
		(property "Value" ""
			(at 0 0 270)
			(layer "F.Fab")
			(effects
				(font
					(size 1.27 1.27)
				)
			)
		)
		(duplicate_pad_numbers_are_jumpers no)
		(fp_line
			(start -0.7874 0.4064)
			(end -0.7874 -0.4064)
			(stroke
				(width 0.1524)
				(type default)
			)
			(layer "F.SilkS")
		)
		(fp_line
			(start 0.7874 0.4064)
			(end -0.7874 0.4064)
			(stroke
				(width 0.1524)
				(type default)
			)
			(layer "F.SilkS")
		)
		(fp_line
			(start -0.7874 -0.4064)
			(end 0.7874 -0.4064)
			(stroke
				(width 0.1524)
				(type default)
			)
			(layer "F.SilkS")
		)
		(fp_line
			(start 0.7874 -0.4064)
			(end 0.7874 0.4064)
			(stroke
				(width 0.1524)
				(type default)
			)
			(layer "F.SilkS")
		)
		(fp_line
			(start -0.67945 0.3048)
			(end -0.67945 -0.305054)
			(stroke
				(width 0.1)
				(type default)
			)
			(layer "F.Fab")
		)
		(fp_line
			(start -0.12065 0.3048)
			(end -0.67945 0.3048)
			(stroke
				(width 0.1)
				(type default)
			)
			(layer "F.Fab")
		)
		(fp_line
			(start 0.120396 0.3048)
			(end 0.120396 0.2794)
			(stroke
				(width 0.1)
				(type default)
			)
			(layer "F.Fab")
		)
		(fp_line
			(start 0.67945 0.3048)
			(end 0.120396 0.3048)
			(stroke
				(width 0.1)
				(type default)
			)
			(layer "F.Fab")
		)
		(fp_line
			(start -0.12065 0.2794)
			(end -0.12065 0.3048)
			(stroke
				(width 0.1)
				(type default)
			)
			(layer "F.Fab")
		)
		(fp_line
			(start 0.120396 0.2794)
			(end -0.12065 0.2794)
			(stroke
				(width 0.1)
				(type default)
			)
			(layer "F.Fab")
		)
		(fp_line
			(start -0.12065 -0.2794)
			(end 0.12065 -0.2794)
			(stroke
				(width 0.1)
				(type default)
			)
			(layer "F.Fab")
		)
		(fp_line
			(start 0.12065 -0.2794)
			(end 0.12065 -0.3048)
			(stroke
				(width 0.1)
				(type default)
			)
			(layer "F.Fab")
		)
		(fp_line
			(start 0.12065 -0.3048)
			(end 0.67945 -0.3048)
			(stroke
				(width 0.1)
				(type default)
			)
			(layer "F.Fab")
		)
		(fp_line
			(start 0.67945 -0.3048)
			(end 0.67945 0.3048)
			(stroke
				(width 0.1)
				(type default)
			)
			(layer "F.Fab")
		)
		(fp_line
			(start -0.67945 -0.305054)
			(end -0.12065 -0.305054)
			(stroke
				(width 0.1)
				(type default)
			)
			(layer "F.Fab")
		)
		(fp_line
			(start -0.12065 -0.305054)
			(end -0.12065 -0.2794)
			(stroke
				(width 0.1)
				(type default)
			)
			(layer "F.Fab")
		)
		(pad "1" smd circle
			(at -0.40005 0 270)
			(size 0 0)
			(layers "F.Cu" "F.Mask" "F.Paste")
			(net "P3V3_NIC6")
		)
		(pad "2" smd circle
			(at 0.40005 0 270)
			(size 0 0)
			(layers "F.Cu" "F.Mask" "F.Paste")
			(net "P3V3_NIC6_PG_G1")
		)
	)
)
